# BASEBOARD_FAB2 (Tioga Pass) — schematic netlist excerpt (pin names and nets, part order shuffled) for the footprints in the layout excerpt that follows; sources: Cadence DE-HDL packaged netlist, KiCad conversion of Wiwynn_Tioga_Pass_MB.brd

J8E3  SCONN80_E67482007  CONN  pkg SM  page 187
  IO1  = FM_MEZZB_PRSNT1_N
  IO2  = P12V_STBY
  IO3  = GND
  IO4  = P12V_STBY
  IO5  = P3E_CPU0_PE3_OCP_RXP<7>
  IO6  = TP_RSVD_B1
  IO7  = P3E_CPU0_PE3_OCP_RXN<7>
  IO8  = GND
  IO9  = GND
  IO10  = P3E_OCP_CPU0_PE3_C_TXP<7>
  IO11  = GND
  IO12  = P3E_OCP_CPU0_PE3_C_TXN<7>
  IO13  = P3E_CPU0_PE3_OCP_RXN<6>
  IO14  = GND
  IO15  = P3E_CPU0_PE3_OCP_RXP<6>
  IO16  = GND
  IO17  = GND
  IO18  = P3E_OCP_CPU0_PE3_C_TXP<6>
  IO19  = GND
  IO20  = P3E_OCP_CPU0_PE3_C_TXN<6>
  IO21  = P3E_CPU0_PE3_OCP_RXN<5>
  IO22  = GND
  IO23  = P3E_CPU0_PE3_OCP_RXP<5>
  IO24  = GND
  IO25  = GND
  IO26  = P3E_OCP_CPU0_PE3_C_TXP<5>
  IO27  = GND
  IO28  = P3E_OCP_CPU0_PE3_C_TXN<5>
  IO29  = P3E_CPU0_PE3_OCP_RXN<4>
  IO30  = GND
  IO31  = P3E_CPU0_PE3_OCP_RXP<4>
  IO32  = GND
  IO33  = GND
  IO34  = P3E_OCP_CPU0_PE3_C_TXP<4>
  IO35  = GND
  IO36  = P3E_OCP_CPU0_PE3_C_TXN<4>
  IO37  = P3E_CPU0_PE3_OCP_RXP<3>
  IO38  = GND
  IO39  = P3E_CPU0_PE3_OCP_RXN<3>
  IO40  = GND
  IO41  = GND
  IO42  = P3E_OCP_CPU0_PE3_C_TXP<3>
  IO43  = GND
  IO44  = P3E_OCP_CPU0_PE3_C_TXN<3>
  IO45  = P3E_CPU0_PE3_OCP_RXP<2>
  IO46  = GND
  IO47  = P3E_CPU0_PE3_OCP_RXN<2>
  IO48  = GND
  IO49  = GND
  IO50  = P3E_OCP_CPU0_PE3_C_TXP<2>
  IO51  = GND
  IO52  = P3E_OCP_CPU0_PE3_C_TXN<2>
  IO53  = P3E_CPU0_PE3_OCP_RXP<1>
  IO54  = GND
  IO55  = P3E_CPU0_PE3_OCP_RXN<1>
  IO56  = GND
  IO57  = GND
  IO58  = P3E_OCP_CPU0_PE3_C_TXP<1>
  IO59  = GND
  IO60  = P3E_OCP_CPU0_PE3_C_TXN<1>
  IO61  = P3E_CPU0_PE3_OCP_RXP<0>
  IO62  = GND
  IO63  = P3E_CPU0_PE3_OCP_RXN<0>
  IO64  = GND
  IO65  = GND
  IO66  = P3E_OCP_CPU0_PE3_C_TXP<0>
  IO67  = GND
  IO68  = P3E_OCP_CPU0_PE3_C_TXN<0>
  IO69  = CLK_100M_MEZZ3_DP
  IO70  = GND
  IO71  = CLK_100M_MEZZ3_DN
  IO72  = GND
  IO73  = GND
  IO74  = CLK_100M_MEZZ4_DP
  IO75  = RST_PCIE_CPU_DEV1_R_N
  IO76  = CLK_100M_MEZZ4_DN
  IO77  = RST_PCIE_CPU_DEV2_R_N
  IO78  = GND
  IO79  = RST_PCIE_CPU_DEV3_R_N
  IO80  = FM_OCP_MEZZB_PRES_N

(kicad_pcb
	(version 20260206)
	(generator "pcbnew")
	(generator_version "10.0")
	(general
		(thickness 1.6)
		(legacy_teardrops no)
	)
	(paper "A4")
	(title_block
		(title "Wiwynn_Tioga_Pass_MB.brd")
		(comment 1 "Tioga Pass / footprint 1403 of 4770 (J8E3), pads 48-82 of 82")
	)
	(layers
		(0 "F.Cu" signal "TOP")
		(4 "In1.Cu" signal "L2GND")
		(6 "In2.Cu" signal "L3")
		(8 "In3.Cu" signal "L4GND")
		(10 "In4.Cu" signal "L5")
		(12 "In5.Cu" signal "L6GND")
		(14 "In6.Cu" signal "L7VCC")
		(16 "In7.Cu" signal "L8VCC")
		(18 "In8.Cu" signal "L9GND")
		(20 "In9.Cu" signal "L10")
		(22 "In10.Cu" signal "L11GND")
		(24 "In11.Cu" signal "L12")
		(26 "In12.Cu" signal "L13GND")
		(2 "B.Cu" signal "BOTTOM")
		(9 "F.Adhes" user "F.Adhesive")
		(11 "B.Adhes" user "B.Adhesive")
		(13 "F.Paste" user "Package Geometry/Pastemask Top")
		(15 "B.Paste" user "Package Geometry/Pastemask Bottom")
		(5 "F.SilkS" user "Ref Des/Silkscreen Top")
		(7 "B.SilkS" user "Ref Des/Silkscreen Bottom")
		(1 "F.Mask" user "Board Geometry/Soldermask Top")
		(3 "B.Mask" user "Board Geometry/Soldermask Bottom")
		(17 "Dwgs.User" user "User.Drawings")
		(19 "Cmts.User" user "User.Comments")
		(21 "Eco1.User" user "User.Eco1")
		(23 "Eco2.User" user "User.Eco2")
		(25 "Edge.Cuts" user "Board Geometry/Outline")
		(27 "Margin" user)
		(31 "F.CrtYd" user "Package Geometry/Place Bound Top")
		(29 "B.CrtYd" user "Package Geometry/Place Bound Bottom")
		(35 "F.Fab" user "Ref Des/Assembly Top")
		(33 "B.Fab" user "Ref Des/Assembly Bottom")
	)
	(footprint ""
		(layer "F.Cu")
		(at 437.34101 -47.481998 90)
		(property "Reference" "J8E3"
			(at 6.402832 -4.049014 0)
			(unlocked yes)
			(layer "F.SilkS")
			(effects
				(font
					(size 0.7874 0.5842)
					(thickness 0.1524)
				)
				(justify left)
			)
		)
		(property "Value" ""
			(at 0 0 90)
			(layer "F.Fab")
			(effects
				(font
					(size 1.27 1.27)
				)
			)
		)
		(duplicate_pad_numbers_are_jumpers no)
		(pad "46" smd rect
			(at 4.393946 17.599914 90)
			(size 2.0066 0.508)
			(layers "F.Cu" "F.Mask" "F.Paste")
			(net "GND")
		)
		(pad "47" smd rect
			(at 0 18.400014 90)
			(size 2.0066 0.508)
			(layers "F.Cu" "F.Mask" "F.Paste")
			(net "P3E_CPU0_PE3_OCP_RXN<2>")
		)
		(pad "48" smd rect
			(at 4.393946 18.400014 90)
			(size 2.0066 0.508)
			(layers "F.Cu" "F.Mask" "F.Paste")
			(net "GND")
		)
		(pad "49" smd rect
			(at 0 19.200114 90)
			(size 2.0066 0.508)
			(layers "F.Cu" "F.Mask" "F.Paste")
			(net "GND")
		)
		(pad "50" smd rect
			(at 4.393946 19.200114 90)
			(size 2.0066 0.508)
			(layers "F.Cu" "F.Mask" "F.Paste")
			(net "P3E_OCP_CPU0_PE3_C_TXP<2>")
		)
		(pad "51" smd rect
			(at 0 19.99996 90)
			(size 2.0066 0.508)
			(layers "F.Cu" "F.Mask" "F.Paste")
			(net "GND")
		)
		(pad "52" smd rect
			(at 4.393946 19.99996 90)
			(size 2.0066 0.508)
			(layers "F.Cu" "F.Mask" "F.Paste")
			(net "P3E_OCP_CPU0_PE3_C_TXN<2>")
		)
		(pad "53" smd rect
			(at 0 20.80006 90)
			(size 2.0066 0.508)
			(layers "F.Cu" "F.Mask" "F.Paste")
			(net "P3E_CPU0_PE3_OCP_RXP<1>")
		)
		(pad "54" smd rect
			(at 4.393946 20.80006 90)
			(size 2.0066 0.508)
			(layers "F.Cu" "F.Mask" "F.Paste")
			(net "GND")
		)
		(pad "55" smd rect
			(at 0 21.599906 90)
			(size 2.0066 0.508)
			(layers "F.Cu" "F.Mask" "F.Paste")
			(net "P3E_CPU0_PE3_OCP_RXN<1>")
		)
		(pad "56" smd rect
			(at 4.393946 21.599906 90)
			(size 2.0066 0.508)
			(layers "F.Cu" "F.Mask" "F.Paste")
			(net "GND")
		)
		(pad "57" smd rect
			(at 0 22.400006 90)
			(size 2.0066 0.508)
			(layers "F.Cu" "F.Mask" "F.Paste")
			(net "GND")
		)
		(pad "58" smd rect
			(at 4.393946 22.400006 90)
			(size 2.0066 0.508)
			(layers "F.Cu" "F.Mask" "F.Paste")
			(net "P3E_OCP_CPU0_PE3_C_TXP<1>")
		)
		(pad "59" smd rect
			(at 0 23.200106 90)
			(size 2.0066 0.508)
			(layers "F.Cu" "F.Mask" "F.Paste")
			(net "GND")
		)
		(pad "60" smd rect
			(at 4.393946 23.200106 90)
			(size 2.0066 0.508)
			(layers "F.Cu" "F.Mask" "F.Paste")
			(net "P3E_OCP_CPU0_PE3_C_TXN<1>")
		)
		(pad "61" smd rect
			(at 0 23.999952 90)
			(size 2.0066 0.508)
			(layers "F.Cu" "F.Mask" "F.Paste")
			(net "P3E_CPU0_PE3_OCP_RXP<0>")
		)
		(pad "62" smd rect
			(at 4.393946 23.999952 90)
			(size 2.0066 0.508)
			(layers "F.Cu" "F.Mask" "F.Paste")
			(net "GND")
		)
		(pad "63" smd rect
			(at 0 24.800052 90)
			(size 2.0066 0.508)
			(layers "F.Cu" "F.Mask" "F.Paste")
			(net "P3E_CPU0_PE3_OCP_RXN<0>")
		)
		(pad "64" smd rect
			(at 4.393946 24.800052 90)
			(size 2.0066 0.508)
			(layers "F.Cu" "F.Mask" "F.Paste")
			(net "GND")
		)
		(pad "65" smd rect
			(at 0 25.599898 90)
			(size 2.0066 0.508)
			(layers "F.Cu" "F.Mask" "F.Paste")
			(net "GND")
		)
		(pad "66" smd rect
			(at 4.393946 25.599898 90)
			(size 2.0066 0.508)
			(layers "F.Cu" "F.Mask" "F.Paste")
			(net "P3E_OCP_CPU0_PE3_C_TXP<0>")
		)
		(pad "67" smd rect
			(at 0 26.399998 90)
			(size 2.0066 0.508)
			(layers "F.Cu" "F.Mask" "F.Paste")
			(net "GND")
		)
		(pad "68" smd rect
			(at 4.393946 26.399998 90)
			(size 2.0066 0.508)
			(layers "F.Cu" "F.Mask" "F.Paste")
			(net "P3E_OCP_CPU0_PE3_C_TXN<0>")
		)
		(pad "69" smd rect
			(at 0 27.200098 90)
			(size 2.0066 0.508)
			(layers "F.Cu" "F.Mask" "F.Paste")
			(net "CLK_100M_MEZZ3_DP")
		)
		(pad "70" smd rect
			(at 4.393946 27.200098 90)
			(size 2.0066 0.508)
			(layers "F.Cu" "F.Mask" "F.Paste")
			(net "GND")
		)
		(pad "71" smd rect
			(at 0 27.999944 90)
			(size 2.0066 0.508)
			(layers "F.Cu" "F.Mask" "F.Paste")
			(net "CLK_100M_MEZZ3_DN")
		)
		(pad "72" smd rect
			(at 4.393946 27.999944 90)
			(size 2.0066 0.508)
			(layers "F.Cu" "F.Mask" "F.Paste")
			(net "GND")
		)
		(pad "73" smd rect
			(at 0 28.800044 90)
			(size 2.0066 0.508)
			(layers "F.Cu" "F.Mask" "F.Paste")
			(net "GND")
		)
		(pad "74" smd rect
			(at 4.393946 28.800044 90)
			(size 2.0066 0.508)
			(layers "F.Cu" "F.Mask" "F.Paste")
			(net "CLK_100M_MEZZ4_DP")
		)
		(pad "75" smd rect
			(at 0 29.59989 90)
			(size 2.0066 0.508)
			(layers "F.Cu" "F.Mask" "F.Paste")
			(net "RST_PCIE_CPU_DEV1_R_N")
		)
		(pad "76" smd rect
			(at 4.393946 29.59989 90)
			(size 2.0066 0.508)
			(layers "F.Cu" "F.Mask" "F.Paste")
			(net "CLK_100M_MEZZ4_DN")
		)
		(pad "77" smd rect
			(at 0 30.39999 90)
			(size 2.0066 0.508)
			(layers "F.Cu" "F.Mask" "F.Paste")
			(net "RST_PCIE_CPU_DEV2_R_N")
		)
		(pad "78" smd rect
			(at 4.393946 30.39999 90)
			(size 2.0066 0.508)
			(layers "F.Cu" "F.Mask" "F.Paste")
			(net "GND")
		)
		(pad "79" smd rect
			(at 0 31.20009 90)
			(size 2.0066 0.508)
			(layers "F.Cu" "F.Mask" "F.Paste")
			(net "RST_PCIE_CPU_DEV3_R_N")
		)
		(pad "80" smd rect
			(at 4.393946 31.20009 90)
			(size 2.0066 0.508)
			(layers "F.Cu" "F.Mask" "F.Paste")
			(net "FM_OCP_MEZZB_PRES_N")
		)
	)
)
